(kicad_pcb
	(version 20260206)
	(generator "pcbnew")
	(generator_version "10.0")
	(general
		(thickness 1.6)
		(legacy_teardrops no)
	)
	(paper "A4")
	(title_block
		(title "timecard-production-celestica-r4006 — R4006-B0001-02_R01.brd")
		(comment 1 "Time Appliance Project (Time Card) / footprints 378-383 of 1113")
	)
	(layers
		(0 "F.Cu" signal "TOP")
		(4 "In1.Cu" signal "L02_GND1")
		(6 "In2.Cu" signal "L03_SIG1")
		(8 "In3.Cu" signal "L04_GND2")
		(10 "In4.Cu" signal "L05_VCC1")
		(12 "In5.Cu" signal "L06_VCC2")
		(14 "In6.Cu" signal "L07_GND3")
		(16 "In7.Cu" signal "L08_SIG2")
		(18 "In8.Cu" signal "L09_GND4")
		(2 "B.Cu" signal "BOTTOM")
		(9 "F.Adhes" user "F.Adhesive")
		(11 "B.Adhes" user "B.Adhesive")
		(13 "F.Paste" user "Package Geometry/Pastemask Top")
		(15 "B.Paste" user "Package Geometry/Pastemask Bottom")
		(5 "F.SilkS" user "Ref Des/Silkscreen Top")
		(7 "B.SilkS" user "Ref Des/Silkscreen Bottom")
		(1 "F.Mask" user "Board Geometry/Soldermask Top")
		(3 "B.Mask" user "Board Geometry/Soldermask Bottom")
		(17 "Dwgs.User" user "User.Drawings")
		(19 "Cmts.User" user "User.Comments")
		(21 "Eco1.User" user "User.Eco1")
		(23 "Eco2.User" user "User.Eco2")
		(25 "Edge.Cuts" user "Board Geometry/Outline")
		(27 "Margin" user)
		(31 "F.CrtYd" user "Package Geometry/Place Bound Top")
		(29 "B.CrtYd" user "Package Geometry/Place Bound Bottom")
		(35 "F.Fab" user "Ref Des/Assembly Top")
		(33 "B.Fab" user "Ref Des/Assembly Bottom")
	)
	(footprint ""
		(layer "F.Cu")
		(at 125.499876 -78.650084)
		(property "Reference" "ME4"
			(at -1.230376 -4.114546 0)
			(unlocked yes)
			(layer "F.SilkS")
			(effects
				(font
					(size 0.7874 0.5842)
					(thickness 0.1524)
				)
				(justify left)
			)
		)
		(property "Value" ""
			(at 0 0 0)
			(layer "F.Fab")
			(effects
				(font
					(size 1.27 1.27)
				)
			)
		)
		(property "User Part Number" "PARTNUM*"
			(at -3.048 5.242306 0)
			(unlocked yes)
			(layer "Cmts.User")
			(hide yes)
			(effects
				(font
					(size 0.7874 0.5842)
					(thickness 0.1524)
				)
				(justify left)
			)
		)
		(property "Device Type" "NUT-G340-10437-01"
			(at -1.4732 4.226306 0)
			(unlocked yes)
			(layer "F.Fab")
			(hide yes)
			(effects
				(font
					(size 0.7874 0.5842)
					(thickness 0.1524)
				)
				(justify left)
			)
		)
		(duplicate_pad_numbers_are_jumpers no)
		(fp_circle
			(center 0 0)
			(end 3.3528 0)
			(stroke
				(width 0.1)
				(type default)
			)
			(fill no)
			(layer "F.SilkS")
		)
		(fp_poly
			(pts
				(arc
					(start -2.102612 -0.1524)
					(mid -1.490671 -1.490671)
					(end -0.1524 -2.102612)
				)
				(arc
					(start -0.1524 -3.171444)
					(mid -2.245137 -2.245137)
					(end -3.171444 -0.1524)
				)
			)
			(stroke
				(width 0)
				(type default)
			)
			(fill yes)
			(layer "F.Paste")
		)
		(fp_poly
			(pts
				(arc
					(start -0.1524 2.102612)
					(mid -1.490671 1.490671)
					(end -2.102612 0.1524)
				)
				(arc
					(start -3.171444 0.1524)
					(mid -2.245137 2.245137)
					(end -0.1524 3.171444)
				)
			)
			(stroke
				(width 0)
				(type default)
			)
			(fill yes)
			(layer "F.Paste")
		)
		(fp_poly
			(pts
				(arc
					(start 0.1524 -2.102612)
					(mid 1.490671 -1.490671)
					(end 2.102612 -0.1524)
				)
				(arc
					(start 3.171444 -0.1524)
					(mid 2.245137 -2.245137)
					(end 0.1524 -3.171444)
				)
			)
			(stroke
				(width 0)
				(type default)
			)
			(fill yes)
			(layer "F.Paste")
		)
		(fp_poly
			(pts
				(arc
					(start 2.102612 0.1524)
					(mid 1.490671 1.490671)
					(end 0.1524 2.102612)
				)
				(arc
					(start 0.1524 3.171444)
					(mid 2.245137 2.245137)
					(end 3.171444 0.1524)
				)
			)
			(stroke
				(width 0)
				(type default)
			)
			(fill yes)
			(layer "F.Paste")
		)
		(fp_rect
			(start -7.5946 7.5946)
			(end 7.5946 -7.5946)
			(stroke
				(width 0)
				(type default)
			)
			(fill no)
			(layer "B.CrtYd")
		)
		(fp_poly
			(pts
				(arc
					(start 3.6068 0)
					(mid -3.6068 0)
					(end 3.6068 0)
				)
			)
			(stroke
				(width 0)
				(type default)
			)
			(fill no)
			(layer "F.CrtYd")
		)
		(fp_circle
			(center 0 0)
			(end 2.8448 0)
			(stroke
				(width 0.1)
				(type default)
			)
			(fill no)
			(layer "F.Fab")
		)
		(pad "1" thru_hole circle
			(at 0 0)
			(size 6.1976 6.1976)
			(drill 4.2164)
			(layers "*.Cu" "*.Mask")
			(remove_unused_layers no)
			(net "SG")
			(padstack
				(mode front_inner_back)
				(layer "Inner"
					(shape circle)
					(size 5.0292 5.0292)
					(clearance -0.1143)
				)
				(layer "B.Cu"
					(shape circle)
					(size 5.0292 5.0292)
				)
			)
		)
	)
	(footprint ""
		(layer "F.Cu")
		(at 125.2982 -63.3222 90)
		(property "Reference" "L6"
			(at -0.762 -1.43383 90)
			(unlocked yes)
			(layer "F.SilkS")
			(effects
				(font
					(size 0.7874 0.5842)
					(thickness 0.1524)
				)
				(justify left)
			)
		)
		(property "Value" "VAL*"
			(at -0.9398 3.70967 90)
			(unlocked yes)
			(layer "F.Fab")
			(hide yes)
			(effects
				(font
					(size 0.7874 0.5842)
					(thickness 0.1524)
				)
				(justify left)
			)
		)
		(property "Device Type" "FERRITEBEAD-G191-10101-01,26OHA"
			(at -0.9906 1.22047 90)
			(unlocked yes)
			(layer "F.Fab")
			(hide yes)
			(effects
				(font
					(size 0.7874 0.5842)
					(thickness 0.1524)
				)
				(justify left)
			)
		)
		(property "User Part Number" "PARTNUM*"
			(at -2.54 2.46507 90)
			(unlocked yes)
			(layer "Cmts.User")
			(hide yes)
			(effects
				(font
					(size 0.7874 0.5842)
					(thickness 0.1524)
				)
				(justify left)
			)
		)
		(property "Tolerance" "TOL*"
			(at -0.9906 5.00507 90)
			(unlocked yes)
			(layer "Cmts.User")
			(hide yes)
			(effects
				(font
					(size 0.7874 0.5842)
					(thickness 0.1524)
				)
				(justify left)
			)
		)
		(duplicate_pad_numbers_are_jumpers no)
		(fp_line
			(start 1.3208 -0.7112)
			(end 1.3208 0.7112)
			(stroke
				(width 0.1)
				(type default)
			)
			(layer "F.SilkS")
		)
		(fp_line
			(start -1.3208 -0.7112)
			(end 1.3208 -0.7112)
			(stroke
				(width 0.1)
				(type default)
			)
			(layer "F.SilkS")
		)
		(fp_line
			(start 1.3208 0.7112)
			(end -1.3208 0.7112)
			(stroke
				(width 0.1)
				(type default)
			)
			(layer "F.SilkS")
		)
		(fp_line
			(start -1.3208 0.7112)
			(end -1.3208 -0.7112)
			(stroke
				(width 0.1)
				(type default)
			)
			(layer "F.SilkS")
		)
		(fp_rect
			(start 1.3208 0.7112)
			(end -1.3208 -0.7112)
			(stroke
				(width 0)
				(type default)
			)
			(fill no)
			(layer "F.CrtYd")
		)
		(fp_line
			(start 0.8128 -0.4572)
			(end 0.8128 0.4572)
			(stroke
				(width 0.1)
				(type default)
			)
			(layer "F.Fab")
		)
		(fp_line
			(start -0.8128 -0.4572)
			(end 0.8128 -0.4572)
			(stroke
				(width 0.1)
				(type default)
			)
			(layer "F.Fab")
		)
		(fp_line
			(start 0.8128 0.4572)
			(end -0.8128 0.4572)
			(stroke
				(width 0.1)
				(type default)
			)
			(layer "F.Fab")
		)
		(fp_line
			(start -0.8128 0.4572)
			(end -0.8128 -0.4572)
			(stroke
				(width 0.1)
				(type default)
			)
			(layer "F.Fab")
		)
		(pad "1" smd rect
			(at -0.6858 0 90)
			(size 0.762 0.8636)
			(layers "F.Cu" "F.Mask" "F.Paste")
			(net "XP3R3V")
		)
		(pad "2" smd rect
			(at 0.6858 0 90)
			(size 0.762 0.8636)
			(layers "F.Cu" "F.Mask" "F.Paste")
			(net "XP1R8V_VIN")
		)
		(zone
			(layer "F.Cu")
			(hatch none 0.5)
			(connect_pads
				(clearance 0)
			)
			(min_thickness 0.25)
			(keepout
				(tracks allowed)
				(vias not_allowed)
				(pads allowed)
				(copperpour not_allowed)
				(footprints allowed)
			)
			(placement
				(enabled no)
				(sheetname "")
			)
			(fill
				(thermal_gap 0.5)
				(thermal_bridge_width 0.5)
				(island_removal_mode 0)
			)
			(polygon
				(pts
					(xy 125.7554 -63.4746) (xy 124.841 -63.4746) (xy 124.841 -63.1698) (xy 125.7554 -63.1698)
				)
			)
		)
	)
	(footprint ""
		(layer "F.Cu")
		(at 98.298 -87.503 90)
		(property "Reference" "R464"
			(at 2.794 -0.59563 90)
			(unlocked yes)
			(layer "F.SilkS")
			(effects
				(font
					(size 0.7874 0.5842)
					(thickness 0.1524)
				)
			)
		)
		(property "Value" "VAL*"
			(at 0.02032 2.13233 90)
			(unlocked yes)
			(layer "F.Fab")
			(hide yes)
			(effects
				(font
					(size 0.7874 0.5842)
					(thickness 0.1524)
				)
			)
		)
		(property "Tolerance" "TOL*"
			(at 0.044704 3.05435 90)
			(unlocked yes)
			(layer "Cmts.User")
			(hide yes)
			(effects
				(font
					(size 0.7874 0.5842)
					(thickness 0.1524)
				)
			)
		)
		(property "User Part Number" "PARTNUM*"
			(at 0.02032 4.024884 90)
			(unlocked yes)
			(layer "Cmts.User")
			(hide yes)
			(effects
				(font
					(size 0.7874 0.5842)
					(thickness 0.1524)
				)
			)
		)
		(property "Device Type" "RESISTOR-G155-100R0-J0,0OHM,-"
			(at 0.008382 1.210564 90)
			(unlocked yes)
			(layer "F.Fab")
			(hide yes)
			(effects
				(font
					(size 0.7874 0.5842)
					(thickness 0.1524)
				)
			)
		)
		(duplicate_pad_numbers_are_jumpers no)
		(fp_line
			(start 1.143 -0.5588)
			(end -1.143 -0.5588)
			(stroke
				(width 0.1)
				(type default)
			)
			(layer "F.SilkS")
		)
		(fp_line
			(start -1.143 -0.5588)
			(end -1.143 0.5588)
			(stroke
				(width 0.1)
				(type default)
			)
			(layer "F.SilkS")
		)
		(fp_line
			(start 1.143 0.5588)
			(end 1.143 -0.5588)
			(stroke
				(width 0.1)
				(type default)
			)
			(layer "F.SilkS")
		)
		(fp_line
			(start -1.143 0.5588)
			(end 1.143 0.5588)
			(stroke
				(width 0.1)
				(type default)
			)
			(layer "F.SilkS")
		)
		(fp_poly
			(pts
				(xy -1.143 0.5588) (xy 1.143 0.5588) (xy 1.143 -0.5588) (xy -1.143 -0.5588)
			)
			(stroke
				(width 0)
				(type default)
			)
			(fill no)
			(layer "F.CrtYd")
		)
		(fp_line
			(start 0.508 -0.3048)
			(end -0.508 -0.3048)
			(stroke
				(width 0.1)
				(type default)
			)
			(layer "F.Fab")
		)
		(fp_line
			(start -0.508 -0.3048)
			(end -0.508 0.3048)
			(stroke
				(width 0.1)
				(type default)
			)
			(layer "F.Fab")
		)
		(fp_line
			(start 0.508 0.3048)
			(end 0.508 -0.3048)
			(stroke
				(width 0.1)
				(type default)
			)
			(layer "F.Fab")
		)
		(fp_line
			(start -0.508 0.3048)
			(end 0.508 0.3048)
			(stroke
				(width 0.1)
				(type default)
			)
			(layer "F.Fab")
		)
		(pad "1" smd rect
			(at -0.5334 0 90)
			(size 0.7112 0.6096)
			(layers "F.Cu" "F.Mask" "F.Paste")
			(net "FPGA_FLASH_DQ2")
		)
		(pad "2" smd rect
			(at 0.5334 0 90)
			(size 0.7112 0.6096)
			(layers "F.Cu" "F.Mask" "F.Paste")
			(net "FLASH_DQ2")
		)
		(zone
			(layer "F.Cu")
			(hatch none 0.5)
			(connect_pads
				(clearance 0)
			)
			(min_thickness 0.25)
			(keepout
				(tracks allowed)
				(vias not_allowed)
				(pads allowed)
				(copperpour not_allowed)
				(footprints allowed)
			)
			(placement
				(enabled no)
				(sheetname "")
			)
			(fill
				(thermal_gap 0.5)
				(thermal_bridge_width 0.5)
				(island_removal_mode 0)
			)
			(polygon
				(pts
					(xy 98.6028 -87.4268) (xy 98.6028 -87.5792) (xy 97.9932 -87.5792) (xy 97.9932 -87.4268)
				)
			)
		)
		(zone
			(layer "F.Cu")
			(hatch none 0.5)
			(connect_pads
				(clearance 0)
			)
			(min_thickness 0.25)
			(keepout
				(tracks not_allowed)
				(vias allowed)
				(pads allowed)
				(copperpour not_allowed)
				(footprints allowed)
			)
			(placement
				(enabled no)
				(sheetname "")
			)
			(fill
				(thermal_gap 0.5)
				(thermal_bridge_width 0.5)
				(island_removal_mode 0)
			)
			(polygon
				(pts
					(xy 98.6028 -87.4268) (xy 98.6028 -87.5792) (xy 97.9932 -87.5792) (xy 97.9932 -87.4268)
				)
			)
		)
	)
	(footprint ""
		(layer "F.Cu")
		(at 12.319 -22.987 90)
		(property "Reference" "R370"
			(at -0.635 -3.26263 90)
			(unlocked yes)
			(layer "F.SilkS")
			(effects
				(font
					(size 0.7874 0.5842)
					(thickness 0.1524)
				)
			)
		)
		(property "Value" "VAL*"
			(at 0.02032 2.13233 90)
			(unlocked yes)
			(layer "F.Fab")
			(hide yes)
			(effects
				(font
					(size 0.7874 0.5842)
					(thickness 0.1524)
				)
			)
		)
		(property "Tolerance" "TOL*"
			(at 0.044704 3.05435 90)
			(unlocked yes)
			(layer "Cmts.User")
			(hide yes)
			(effects
				(font
					(size 0.7874 0.5842)
					(thickness 0.1524)
				)
			)
		)
		(property "User Part Number" "PARTNUM*"
			(at 0.02032 4.024884 90)
			(unlocked yes)
			(layer "Cmts.User")
			(hide yes)
			(effects
				(font
					(size 0.7874 0.5842)
					(thickness 0.1524)
				)
			)
		)
		(property "Device Type" "RESISTOR-G155-149R9-01,49.9OHMA"
			(at 0.008382 1.210564 90)
			(unlocked yes)
			(layer "F.Fab")
			(hide yes)
			(effects
				(font
					(size 0.7874 0.5842)
					(thickness 0.1524)
				)
			)
		)
		(duplicate_pad_numbers_are_jumpers no)
		(fp_line
			(start 1.143 -0.5588)
			(end -1.143 -0.5588)
			(stroke
				(width 0.1)
				(type default)
			)
			(layer "F.SilkS")
		)
		(fp_line
			(start -1.143 -0.5588)
			(end -1.143 0.5588)
			(stroke
				(width 0.1)
				(type default)
			)
			(layer "F.SilkS")
		)
		(fp_line
			(start 1.143 0.5588)
			(end 1.143 -0.5588)
			(stroke
				(width 0.1)
				(type default)
			)
			(layer "F.SilkS")
		)
		(fp_line
			(start -1.143 0.5588)
			(end 1.143 0.5588)
			(stroke
				(width 0.1)
				(type default)
			)
			(layer "F.SilkS")
		)
		(fp_poly
			(pts
				(xy -1.143 0.5588) (xy 1.143 0.5588) (xy 1.143 -0.5588) (xy -1.143 -0.5588)
			)
			(stroke
				(width 0)
				(type default)
			)
			(fill no)
			(layer "F.CrtYd")
		)
		(fp_line
			(start 0.508 -0.3048)
			(end -0.508 -0.3048)
			(stroke
				(width 0.1)
				(type default)
			)
			(layer "F.Fab")
		)
		(fp_line
			(start -0.508 -0.3048)
			(end -0.508 0.3048)
			(stroke
				(width 0.1)
				(type default)
			)
			(layer "F.Fab")
		)
		(fp_line
			(start 0.508 0.3048)
			(end 0.508 -0.3048)
			(stroke
				(width 0.1)
				(type default)
			)
			(layer "F.Fab")
		)
		(fp_line
			(start -0.508 0.3048)
			(end 0.508 0.3048)
			(stroke
				(width 0.1)
				(type default)
			)
			(layer "F.Fab")
		)
		(pad "1" smd rect
			(at -0.5334 0 90)
			(size 0.7112 0.6096)
			(layers "F.Cu" "F.Mask" "F.Paste")
			(net "BF_ANT4_IN")
		)
		(pad "2" smd rect
			(at 0.5334 0 90)
			(size 0.7112 0.6096)
			(layers "F.Cu" "F.Mask" "F.Paste")
			(net "ANT4_IN")
		)
		(zone
			(layer "F.Cu")
			(hatch none 0.5)
			(connect_pads
				(clearance 0)
			)
			(min_thickness 0.25)
			(keepout
				(tracks allowed)
				(vias not_allowed)
				(pads allowed)
				(copperpour not_allowed)
				(footprints allowed)
			)
			(placement
				(enabled no)
				(sheetname "")
			)
			(fill
				(thermal_gap 0.5)
				(thermal_bridge_width 0.5)
				(island_removal_mode 0)
			)
			(polygon
				(pts
					(xy 12.6238 -22.9108) (xy 12.6238 -23.0632) (xy 12.0142 -23.0632) (xy 12.0142 -22.9108)
				)
			)
		)
		(zone
			(layer "F.Cu")
			(hatch none 0.5)
			(connect_pads
				(clearance 0)
			)
			(min_thickness 0.25)
			(keepout
				(tracks not_allowed)
				(vias allowed)
				(pads allowed)
				(copperpour not_allowed)
				(footprints allowed)
			)
			(placement
				(enabled no)
				(sheetname "")
			)
			(fill
				(thermal_gap 0.5)
				(thermal_bridge_width 0.5)
				(island_removal_mode 0)
			)
			(polygon
				(pts
					(xy 12.6238 -22.9108) (xy 12.6238 -23.0632) (xy 12.0142 -23.0632) (xy 12.0142 -22.9108)
				)
			)
		)
	)
	(footprint ""
		(layer "F.Cu")
		(at 46.482 -127.127)
		(property "Reference" "SP66"
			(at 0 0 0)
			(layer "F.SilkS")
			(hide yes)
			(effects
				(font
					(size 1.27 1.27)
				)
			)
		)
		(property "Value" ""
			(at 0 0 0)
			(layer "F.Fab")
			(effects
				(font
					(size 1.27 1.27)
				)
			)
		)
		(duplicate_pad_numbers_are_jumpers no)
	)
	(footprint ""
		(layer "F.Cu")
		(at 122.3264 -31.9532 90)
		(property "Reference" "TP201"
			(at -1.50495 -0.3302 0)
			(unlocked yes)
			(layer "F.SilkS")
			(effects
				(font
					(size 0.635 0.4064)
					(thickness 0.1524)
				)
				(justify left)
			)
		)
		(property "Value" ""
			(at 0 0 90)
			(layer "F.Fab")
			(effects
				(font
					(size 1.27 1.27)
				)
			)
		)
		(property "Device Type" "TP_PIONT-TP010CT020B030_PTH-TPA"
			(at -1.341882 0.996696 90)
			(unlocked yes)
			(layer "F.Fab")
			(hide yes)
			(effects
				(font
					(size 0.7874 0.5842)
					(thickness 0.1524)
				)
				(justify left)
			)
		)
		(duplicate_pad_numbers_are_jumpers no)
		(fp_poly
			(pts
				(arc
					(start 0 0.889)
					(mid 0 -0.889)
					(end 0 0.889)
				)
			)
			(stroke
				(width 0)
				(type default)
			)
			(fill no)
			(layer "B.CrtYd")
		)
		(fp_poly
			(pts
				(arc
					(start 0 0.889)
					(mid 0 -0.889)
					(end 0 0.889)
				)
			)
			(stroke
				(width 0)
				(type default)
			)
			(fill no)
			(layer "F.CrtYd")
		)
		(pad "1" thru_hole circle
			(at 0 0 90)
			(size 0.508 0.508)
			(drill 0.254)
			(layers "*.Cu" "*.Mask")
			(remove_unused_layers no)
			(net "IO_L22P_35")
			(clearance 0.1016)
			(padstack
				(mode front_inner_back)
				(layer "Inner"
					(shape circle)
					(size 0.508 0.508)
					(clearance 0.1016)
				)
				(layer "B.Cu"
					(shape circle)
					(size 0.762 0.762)
					(clearance -0.0254)
				)
			)
		)
	)
)
